(kicad_pcb
	(version 20260206)
	(generator "pcbnew")
	(generator_version "10.0")
	(general
		(thickness 1.6)
		(legacy_teardrops no)
	)
	(paper "A4")
	(title_block
		(title "12092022_DA0F0TMDCD0_F0T_Management_Board_D_brd_V3_OCP.brd")
		(comment 1 "Grand Teton / footprints 638-643 of 1440")
	)
	(layers
		(0 "F.Cu" signal "TOP")
		(4 "In1.Cu" signal "GND")
		(6 "In2.Cu" signal "IN1")
		(8 "In3.Cu" signal "GND1")
		(10 "In4.Cu" signal "IN2")
		(12 "In5.Cu" signal "VCC")
		(14 "In6.Cu" signal "VCC1")
		(16 "In7.Cu" signal "IN3")
		(18 "In8.Cu" signal "GND2")
		(20 "In9.Cu" signal "IN4")
		(22 "In10.Cu" signal "GND3")
		(2 "B.Cu" signal "BOTTOM")
		(9 "F.Adhes" user "F.Adhesive")
		(11 "B.Adhes" user "B.Adhesive")
		(13 "F.Paste" user "Package Geometry/Pastemask Top")
		(15 "B.Paste" user "Package Geometry/Pastemask Bottom")
		(5 "F.SilkS" user "Ref Des/Silkscreen Top")
		(7 "B.SilkS" user "Ref Des/Silkscreen Bottom")
		(1 "F.Mask" user "Board Geometry/Soldermask Top")
		(3 "B.Mask" user "Board Geometry/Soldermask Bottom")
		(17 "Dwgs.User" user "User.Drawings")
		(19 "Cmts.User" user "User.Comments")
		(21 "Eco1.User" user "User.Eco1")
		(23 "Eco2.User" user "User.Eco2")
		(25 "Edge.Cuts" user "Board Geometry/Outline")
		(27 "Margin" user)
		(31 "F.CrtYd" user "Package Geometry/Place Bound Top")
		(29 "B.CrtYd" user "Package Geometry/Place Bound Bottom")
		(35 "F.Fab" user "Ref Des/Assembly Top")
		(33 "B.Fab" user "Ref Des/Assembly Bottom")
	)
	(footprint ""
		(layer "F.Cu")
		(at 59.182 -10.922 90)
		(property "Reference" "C27"
			(at 0 0 90)
			(layer "F.SilkS")
			(hide yes)
			(effects
				(font
					(size 1.27 1.27)
				)
			)
		)
		(property "Value" ""
			(at 0 0 90)
			(layer "F.Fab")
			(effects
				(font
					(size 1.27 1.27)
				)
			)
		)
		(duplicate_pad_numbers_are_jumpers no)
		(fp_line
			(start -0.492506 -0.4064)
			(end 0.421894 -0.4064)
			(stroke
				(width 0.1524)
				(type default)
			)
			(layer "F.SilkS")
		)
		(fp_line
			(start 0.7874 -0.077216)
			(end 0.7874 0.4064)
			(stroke
				(width 0.1524)
				(type default)
			)
			(layer "F.SilkS")
		)
		(fp_line
			(start 0.7874 0.4064)
			(end -0.7874 0.4064)
			(stroke
				(width 0.1524)
				(type default)
			)
			(layer "F.SilkS")
		)
		(fp_line
			(start -0.7874 0.4064)
			(end -0.7874 -0.039116)
			(stroke
				(width 0.1524)
				(type default)
			)
			(layer "F.SilkS")
		)
		(fp_line
			(start -0.12065 -0.305054)
			(end -0.12065 -0.2794)
			(stroke
				(width 0.1)
				(type default)
			)
			(layer "F.Fab")
		)
		(fp_line
			(start -0.67945 -0.305054)
			(end -0.12065 -0.305054)
			(stroke
				(width 0.1)
				(type default)
			)
			(layer "F.Fab")
		)
		(fp_line
			(start 0.67945 -0.3048)
			(end 0.67945 0.3048)
			(stroke
				(width 0.1)
				(type default)
			)
			(layer "F.Fab")
		)
		(fp_line
			(start 0.12065 -0.3048)
			(end 0.67945 -0.3048)
			(stroke
				(width 0.1)
				(type default)
			)
			(layer "F.Fab")
		)
		(fp_line
			(start 0.12065 -0.2794)
			(end 0.12065 -0.3048)
			(stroke
				(width 0.1)
				(type default)
			)
			(layer "F.Fab")
		)
		(fp_line
			(start -0.12065 -0.2794)
			(end 0.12065 -0.2794)
			(stroke
				(width 0.1)
				(type default)
			)
			(layer "F.Fab")
		)
		(fp_line
			(start 0.120396 0.2794)
			(end -0.12065 0.2794)
			(stroke
				(width 0.1)
				(type default)
			)
			(layer "F.Fab")
		)
		(fp_line
			(start -0.12065 0.2794)
			(end -0.12065 0.3048)
			(stroke
				(width 0.1)
				(type default)
			)
			(layer "F.Fab")
		)
		(fp_line
			(start 0.67945 0.3048)
			(end 0.120396 0.3048)
			(stroke
				(width 0.1)
				(type default)
			)
			(layer "F.Fab")
		)
		(fp_line
			(start 0.120396 0.3048)
			(end 0.120396 0.2794)
			(stroke
				(width 0.1)
				(type default)
			)
			(layer "F.Fab")
		)
		(fp_line
			(start -0.12065 0.3048)
			(end -0.67945 0.3048)
			(stroke
				(width 0.1)
				(type default)
			)
			(layer "F.Fab")
		)
		(fp_line
			(start -0.67945 0.3048)
			(end -0.67945 -0.305054)
			(stroke
				(width 0.1)
				(type default)
			)
			(layer "F.Fab")
		)
		(pad "1" smd circle
			(at -0.40005 0 90)
			(size 0 0)
			(layers "F.Cu" "F.Mask" "F.Paste")
			(net "LED_D22_R")
		)
		(pad "2" smd circle
			(at 0.40005 0 90)
			(size 0 0)
			(layers "F.Cu" "F.Mask" "F.Paste")
			(net "GND")
		)
	)
	(footprint ""
		(layer "F.Cu")
		(at 43.9166 -69.2912 180)
		(property "Reference" "R167"
			(at 0 0 180)
			(layer "F.SilkS")
			(hide yes)
			(effects
				(font
					(size 1.27 1.27)
				)
			)
		)
		(property "Value" ""
			(at 0 0 180)
			(layer "F.Fab")
			(effects
				(font
					(size 1.27 1.27)
				)
			)
		)
		(duplicate_pad_numbers_are_jumpers no)
		(fp_line
			(start 0.7874 0.4064)
			(end -0.7874 0.4064)
			(stroke
				(width 0.1524)
				(type default)
			)
			(layer "F.SilkS")
		)
		(fp_line
			(start 0.7874 -0.4064)
			(end 0.7874 0.4064)
			(stroke
				(width 0.1524)
				(type default)
			)
			(layer "F.SilkS")
		)
		(fp_line
			(start -0.7874 0.4064)
			(end -0.7874 -0.4064)
			(stroke
				(width 0.1524)
				(type default)
			)
			(layer "F.SilkS")
		)
		(fp_line
			(start -0.7874 -0.4064)
			(end 0.7874 -0.4064)
			(stroke
				(width 0.1524)
				(type default)
			)
			(layer "F.SilkS")
		)
		(fp_line
			(start 0.67945 0.3048)
			(end 0.120396 0.3048)
			(stroke
				(width 0.1)
				(type default)
			)
			(layer "F.Fab")
		)
		(fp_line
			(start 0.67945 -0.3048)
			(end 0.67945 0.3048)
			(stroke
				(width 0.1)
				(type default)
			)
			(layer "F.Fab")
		)
		(fp_line
			(start 0.12065 -0.2794)
			(end 0.12065 -0.3048)
			(stroke
				(width 0.1)
				(type default)
			)
			(layer "F.Fab")
		)
		(fp_line
			(start 0.12065 -0.3048)
			(end 0.67945 -0.3048)
			(stroke
				(width 0.1)
				(type default)
			)
			(layer "F.Fab")
		)
		(fp_line
			(start 0.120396 0.3048)
			(end 0.120396 0.2794)
			(stroke
				(width 0.1)
				(type default)
			)
			(layer "F.Fab")
		)
		(fp_line
			(start 0.120396 0.2794)
			(end -0.12065 0.2794)
			(stroke
				(width 0.1)
				(type default)
			)
			(layer "F.Fab")
		)
		(fp_line
			(start -0.12065 0.3048)
			(end -0.67945 0.3048)
			(stroke
				(width 0.1)
				(type default)
			)
			(layer "F.Fab")
		)
		(fp_line
			(start -0.12065 0.2794)
			(end -0.12065 0.3048)
			(stroke
				(width 0.1)
				(type default)
			)
			(layer "F.Fab")
		)
		(fp_line
			(start -0.12065 -0.2794)
			(end 0.12065 -0.2794)
			(stroke
				(width 0.1)
				(type default)
			)
			(layer "F.Fab")
		)
		(fp_line
			(start -0.12065 -0.305054)
			(end -0.12065 -0.2794)
			(stroke
				(width 0.1)
				(type default)
			)
			(layer "F.Fab")
		)
		(fp_line
			(start -0.67945 0.3048)
			(end -0.67945 -0.305054)
			(stroke
				(width 0.1)
				(type default)
			)
			(layer "F.Fab")
		)
		(fp_line
			(start -0.67945 -0.305054)
			(end -0.12065 -0.305054)
			(stroke
				(width 0.1)
				(type default)
			)
			(layer "F.Fab")
		)
		(pad "1" smd circle
			(at -0.40005 0 180)
			(size 0 0)
			(layers "F.Cu" "F.Mask" "F.Paste")
			(net "P3V3_AUX")
		)
		(pad "2" smd circle
			(at 0.40005 0 180)
			(size 0 0)
			(layers "F.Cu" "F.Mask" "F.Paste")
			(net "BMC_HEARTBEAT_R_N")
		)
	)
	(footprint ""
		(layer "F.Cu")
		(at 75.946 -77.978)
		(property "Reference" "R677"
			(at 0 0 0)
			(layer "F.SilkS")
			(hide yes)
			(effects
				(font
					(size 1.27 1.27)
				)
			)
		)
		(property "Value" ""
			(at 0 0 0)
			(layer "F.Fab")
			(effects
				(font
					(size 1.27 1.27)
				)
			)
		)
		(duplicate_pad_numbers_are_jumpers no)
		(fp_line
			(start -0.7874 -0.4064)
			(end 0.7874 -0.4064)
			(stroke
				(width 0.1524)
				(type default)
			)
			(layer "F.SilkS")
		)
		(fp_line
			(start -0.7874 0.4064)
			(end -0.7874 -0.4064)
			(stroke
				(width 0.1524)
				(type default)
			)
			(layer "F.SilkS")
		)
		(fp_line
			(start 0.7874 -0.4064)
			(end 0.7874 0.4064)
			(stroke
				(width 0.1524)
				(type default)
			)
			(layer "F.SilkS")
		)
		(fp_line
			(start 0.7874 0.4064)
			(end -0.7874 0.4064)
			(stroke
				(width 0.1524)
				(type default)
			)
			(layer "F.SilkS")
		)
		(fp_line
			(start -0.67945 -0.305054)
			(end -0.12065 -0.305054)
			(stroke
				(width 0.1)
				(type default)
			)
			(layer "F.Fab")
		)
		(fp_line
			(start -0.67945 0.3048)
			(end -0.67945 -0.305054)
			(stroke
				(width 0.1)
				(type default)
			)
			(layer "F.Fab")
		)
		(fp_line
			(start -0.12065 -0.305054)
			(end -0.12065 -0.2794)
			(stroke
				(width 0.1)
				(type default)
			)
			(layer "F.Fab")
		)
		(fp_line
			(start -0.12065 -0.2794)
			(end 0.12065 -0.2794)
			(stroke
				(width 0.1)
				(type default)
			)
			(layer "F.Fab")
		)
		(fp_line
			(start -0.12065 0.2794)
			(end -0.12065 0.3048)
			(stroke
				(width 0.1)
				(type default)
			)
			(layer "F.Fab")
		)
		(fp_line
			(start -0.12065 0.3048)
			(end -0.67945 0.3048)
			(stroke
				(width 0.1)
				(type default)
			)
			(layer "F.Fab")
		)
		(fp_line
			(start 0.120396 0.2794)
			(end -0.12065 0.2794)
			(stroke
				(width 0.1)
				(type default)
			)
			(layer "F.Fab")
		)
		(fp_line
			(start 0.120396 0.3048)
			(end 0.120396 0.2794)
			(stroke
				(width 0.1)
				(type default)
			)
			(layer "F.Fab")
		)
		(fp_line
			(start 0.12065 -0.3048)
			(end 0.67945 -0.3048)
			(stroke
				(width 0.1)
				(type default)
			)
			(layer "F.Fab")
		)
		(fp_line
			(start 0.12065 -0.2794)
			(end 0.12065 -0.3048)
			(stroke
				(width 0.1)
				(type default)
			)
			(layer "F.Fab")
		)
		(fp_line
			(start 0.67945 -0.3048)
			(end 0.67945 0.3048)
			(stroke
				(width 0.1)
				(type default)
			)
			(layer "F.Fab")
		)
		(fp_line
			(start 0.67945 0.3048)
			(end 0.120396 0.3048)
			(stroke
				(width 0.1)
				(type default)
			)
			(layer "F.Fab")
		)
		(pad "1" smd circle
			(at -0.40005 0)
			(size 0 0)
			(layers "F.Cu" "F.Mask" "F.Paste")
			(net "U56_ADJ_1")
		)
		(pad "2" smd circle
			(at 0.40005 0)
			(size 0 0)
			(layers "F.Cu" "F.Mask" "F.Paste")
			(net "GND")
		)
	)
	(footprint ""
		(layer "F.Cu")
		(at 75.646534 -28.196032 -90)
		(property "Reference" "D2"
			(at 2.282952 -8.41883 90)
			(unlocked yes)
			(layer "F.SilkS")
			(effects
				(font
					(size 0.7874 0.5842)
					(thickness 0.1524)
				)
				(justify left)
			)
		)
		(property "Value" ""
			(at 0 0 270)
			(layer "F.Fab")
			(effects
				(font
					(size 1.27 1.27)
				)
			)
		)
		(duplicate_pad_numbers_are_jumpers no)
		(fp_line
			(start -1.3208 0.5588)
			(end -1.3208 -0.5588)
			(stroke
				(width 0.1524)
				(type default)
			)
			(layer "F.SilkS")
		)
		(fp_line
			(start 1.3208 0.5588)
			(end -1.3208 0.5588)
			(stroke
				(width 0.1524)
				(type default)
			)
			(layer "F.SilkS")
		)
		(fp_line
			(start 1.6256 0.5588)
			(end 1.6256 -0.5588)
			(stroke
				(width 0.1524)
				(type default)
			)
			(layer "F.SilkS")
		)
		(fp_line
			(start 1.778 0.5588)
			(end 1.3208 0.5588)
			(stroke
				(width 0.1524)
				(type default)
			)
			(layer "F.SilkS")
		)
		(fp_line
			(start -1.3208 -0.5588)
			(end 1.3208 -0.5588)
			(stroke
				(width 0.1524)
				(type default)
			)
			(layer "F.SilkS")
		)
		(fp_line
			(start 1.3208 -0.5588)
			(end 1.3208 0.5588)
			(stroke
				(width 0.1524)
				(type default)
			)
			(layer "F.SilkS")
		)
		(fp_line
			(start 1.4732 -0.5588)
			(end 1.4732 0.5588)
			(stroke
				(width 0.1524)
				(type default)
			)
			(layer "F.SilkS")
		)
		(fp_line
			(start 1.778 -0.5588)
			(end 1.778 0.5588)
			(stroke
				(width 0.1524)
				(type default)
			)
			(layer "F.SilkS")
		)
		(fp_line
			(start 1.778 -0.5588)
			(end 1.3208 -0.5588)
			(stroke
				(width 0.1524)
				(type default)
			)
			(layer "F.SilkS")
		)
		(fp_line
			(start -1.235964 0.508)
			(end -1.1684 0.508)
			(stroke
				(width 0.1)
				(type default)
			)
			(layer "F.Fab")
		)
		(fp_line
			(start -1.1684 0.508)
			(end 1.1684 0.508)
			(stroke
				(width 0.1)
				(type default)
			)
			(layer "F.Fab")
		)
		(fp_line
			(start 1.1684 0.508)
			(end 1.236726 0.508)
			(stroke
				(width 0.1)
				(type default)
			)
			(layer "F.Fab")
		)
		(fp_line
			(start 1.236726 0.508)
			(end 1.236726 -0.508)
			(stroke
				(width 0.1)
				(type default)
			)
			(layer "F.Fab")
		)
		(fp_line
			(start -1.235964 -0.508)
			(end -1.235964 0.508)
			(stroke
				(width 0.1)
				(type default)
			)
			(layer "F.Fab")
		)
		(fp_line
			(start -1.1684 -0.508)
			(end -1.235964 -0.508)
			(stroke
				(width 0.1)
				(type default)
			)
			(layer "F.Fab")
		)
		(fp_line
			(start 1.1684 -0.508)
			(end -1.1684 -0.508)
			(stroke
				(width 0.1)
				(type default)
			)
			(layer "F.Fab")
		)
		(fp_line
			(start 1.236726 -0.508)
			(end 1.1684 -0.508)
			(stroke
				(width 0.1)
				(type default)
			)
			(layer "F.Fab")
		)
		(fp_text user "+"
			(at -0.861568 1.014984 90)
			(unlocked yes)
			(layer "F.SilkS")
			(effects
				(font
					(size 1.905 1.4224)
					(thickness 0.1524)
				)
				(justify left)
			)
		)
		(fp_text user "-"
			(at 1.678432 -1.055116 270)
			(unlocked yes)
			(layer "F.SilkS")
			(effects
				(font
					(size 1.905 1.4224)
					(thickness 0.1524)
				)
				(justify left)
			)
		)
		(fp_text user "+"
			(at -2.5654 -0.24765 270)
			(unlocked yes)
			(layer "F.Fab")
			(effects
				(font
					(size 1.905 1.4224)
					(thickness 0.1524)
				)
				(justify left)
			)
		)
		(fp_text user "-"
			(at 1.524 -0.24765 270)
			(unlocked yes)
			(layer "F.Fab")
			(effects
				(font
					(size 1.905 1.4224)
					(thickness 0.1524)
				)
				(justify left)
			)
		)
		(pad "A" smd rect
			(at -0.750062 0 270)
			(size 0.8128 0.8128)
			(layers "F.Cu" "F.Mask" "F.Paste")
			(net "LED_POSTCODE_2_R")
		)
		(pad "C" smd rect
			(at 0.750062 0 270)
			(size 0.8128 0.8128)
			(layers "F.Cu" "F.Mask" "F.Paste")
			(net "GND")
		)
	)
	(footprint ""
		(layer "F.Cu")
		(at 25.06472 -108.4453 90)
		(property "Reference" "R313"
			(at 0 0 90)
			(layer "F.SilkS")
			(hide yes)
			(effects
				(font
					(size 1.27 1.27)
				)
			)
		)
		(property "Value" ""
			(at 0 0 90)
			(layer "F.Fab")
			(effects
				(font
					(size 1.27 1.27)
				)
			)
		)
		(duplicate_pad_numbers_are_jumpers no)
		(fp_line
			(start 0.7874 -0.4064)
			(end 0.7874 0.4064)
			(stroke
				(width 0.1524)
				(type default)
			)
			(layer "F.SilkS")
		)
		(fp_line
			(start -0.7874 -0.4064)
			(end 0.7874 -0.4064)
			(stroke
				(width 0.1524)
				(type default)
			)
			(layer "F.SilkS")
		)
		(fp_line
			(start 0.7874 0.4064)
			(end -0.7874 0.4064)
			(stroke
				(width 0.1524)
				(type default)
			)
			(layer "F.SilkS")
		)
		(fp_line
			(start -0.7874 0.4064)
			(end -0.7874 -0.4064)
			(stroke
				(width 0.1524)
				(type default)
			)
			(layer "F.SilkS")
		)
		(fp_line
			(start -0.12065 -0.305054)
			(end -0.12065 -0.2794)
			(stroke
				(width 0.1)
				(type default)
			)
			(layer "F.Fab")
		)
		(fp_line
			(start -0.67945 -0.305054)
			(end -0.12065 -0.305054)
			(stroke
				(width 0.1)
				(type default)
			)
			(layer "F.Fab")
		)
		(fp_line
			(start 0.67945 -0.3048)
			(end 0.67945 0.3048)
			(stroke
				(width 0.1)
				(type default)
			)
			(layer "F.Fab")
		)
		(fp_line
			(start 0.12065 -0.3048)
			(end 0.67945 -0.3048)
			(stroke
				(width 0.1)
				(type default)
			)
			(layer "F.Fab")
		)
		(fp_line
			(start 0.12065 -0.2794)
			(end 0.12065 -0.3048)
			(stroke
				(width 0.1)
				(type default)
			)
			(layer "F.Fab")
		)
		(fp_line
			(start -0.12065 -0.2794)
			(end 0.12065 -0.2794)
			(stroke
				(width 0.1)
				(type default)
			)
			(layer "F.Fab")
		)
		(fp_line
			(start 0.120396 0.2794)
			(end -0.12065 0.2794)
			(stroke
				(width 0.1)
				(type default)
			)
			(layer "F.Fab")
		)
		(fp_line
			(start -0.12065 0.2794)
			(end -0.12065 0.3048)
			(stroke
				(width 0.1)
				(type default)
			)
			(layer "F.Fab")
		)
		(fp_line
			(start 0.67945 0.3048)
			(end 0.120396 0.3048)
			(stroke
				(width 0.1)
				(type default)
			)
			(layer "F.Fab")
		)
		(fp_line
			(start 0.120396 0.3048)
			(end 0.120396 0.2794)
			(stroke
				(width 0.1)
				(type default)
			)
			(layer "F.Fab")
		)
		(fp_line
			(start -0.12065 0.3048)
			(end -0.67945 0.3048)
			(stroke
				(width 0.1)
				(type default)
			)
			(layer "F.Fab")
		)
		(fp_line
			(start -0.67945 0.3048)
			(end -0.67945 -0.305054)
			(stroke
				(width 0.1)
				(type default)
			)
			(layer "F.Fab")
		)
		(pad "1" smd circle
			(at -0.40005 0 90)
			(size 0 0)
			(layers "F.Cu" "F.Mask" "F.Paste")
			(net "RST_BMC_SELF_HW_D")
		)
		(pad "2" smd circle
			(at 0.40005 0 90)
			(size 0 0)
			(layers "F.Cu" "F.Mask" "F.Paste")
			(net "GND")
		)
	)
	(footprint ""
		(layer "F.Cu")
		(at 56.3372 -63.6524 90)
		(property "Reference" "R494"
			(at 0 0 90)
			(layer "F.SilkS")
			(hide yes)
			(effects
				(font
					(size 1.27 1.27)
				)
			)
		)
		(property "Value" ""
			(at 0 0 90)
			(layer "F.Fab")
			(effects
				(font
					(size 1.27 1.27)
				)
			)
		)
		(duplicate_pad_numbers_are_jumpers no)
		(fp_line
			(start 0.7874 -0.4064)
			(end 0.7874 0.4064)
			(stroke
				(width 0.1524)
				(type default)
			)
			(layer "F.SilkS")
		)
		(fp_line
			(start -0.7874 -0.4064)
			(end 0.7874 -0.4064)
			(stroke
				(width 0.1524)
				(type default)
			)
			(layer "F.SilkS")
		)
		(fp_line
			(start 0.7874 0.4064)
			(end -0.7874 0.4064)
			(stroke
				(width 0.1524)
				(type default)
			)
			(layer "F.SilkS")
		)
		(fp_line
			(start -0.7874 0.4064)
			(end -0.7874 -0.4064)
			(stroke
				(width 0.1524)
				(type default)
			)
			(layer "F.SilkS")
		)
		(fp_line
			(start -0.12065 -0.305054)
			(end -0.12065 -0.2794)
			(stroke
				(width 0.1)
				(type default)
			)
			(layer "F.Fab")
		)
		(fp_line
			(start -0.67945 -0.305054)
			(end -0.12065 -0.305054)
			(stroke
				(width 0.1)
				(type default)
			)
			(layer "F.Fab")
		)
		(fp_line
			(start 0.67945 -0.3048)
			(end 0.67945 0.3048)
			(stroke
				(width 0.1)
				(type default)
			)
			(layer "F.Fab")
		)
		(fp_line
			(start 0.12065 -0.3048)
			(end 0.67945 -0.3048)
			(stroke
				(width 0.1)
				(type default)
			)
			(layer "F.Fab")
		)
		(fp_line
			(start 0.12065 -0.2794)
			(end 0.12065 -0.3048)
			(stroke
				(width 0.1)
				(type default)
			)
			(layer "F.Fab")
		)
		(fp_line
			(start -0.12065 -0.2794)
			(end 0.12065 -0.2794)
			(stroke
				(width 0.1)
				(type default)
			)
			(layer "F.Fab")
		)
		(fp_line
			(start 0.120396 0.2794)
			(end -0.12065 0.2794)
			(stroke
				(width 0.1)
				(type default)
			)
			(layer "F.Fab")
		)
		(fp_line
			(start -0.12065 0.2794)
			(end -0.12065 0.3048)
			(stroke
				(width 0.1)
				(type default)
			)
			(layer "F.Fab")
		)
		(fp_line
			(start 0.67945 0.3048)
			(end 0.120396 0.3048)
			(stroke
				(width 0.1)
				(type default)
			)
			(layer "F.Fab")
		)
		(fp_line
			(start 0.120396 0.3048)
			(end 0.120396 0.2794)
			(stroke
				(width 0.1)
				(type default)
			)
			(layer "F.Fab")
		)
		(fp_line
			(start -0.12065 0.3048)
			(end -0.67945 0.3048)
			(stroke
				(width 0.1)
				(type default)
			)
			(layer "F.Fab")
		)
		(fp_line
			(start -0.67945 0.3048)
			(end -0.67945 -0.305054)
			(stroke
				(width 0.1)
				(type default)
			)
			(layer "F.Fab")
		)
		(pad "1" smd circle
			(at -0.40005 0 90)
			(size 0 0)
			(layers "F.Cu" "F.Mask" "F.Paste")
			(net "RST_BMC_SELF_HW_R1")
		)
		(pad "2" smd circle
			(at 0.40005 0 90)
			(size 0 0)
			(layers "F.Cu" "F.Mask" "F.Paste")
			(net "RST_BMC_SELF_HW")
		)
	)
)
